(kicad_pcb
	(version 20260206)
	(generator "pcbnew")
	(generator_version "10.0")
	(general
		(thickness 1.6)
		(legacy_teardrops no)
	)
	(paper "A4")
	(title_block
		(title "dpb — 14545-sa.0730WZS0815.brd")
		(comment 1 "Honey Badger (Wiwynn) / footprints 842-844 of 1066")
	)
	(layers
		(0 "F.Cu" signal "TOP")
		(4 "In1.Cu" signal "L2GND")
		(6 "In2.Cu" signal "L3")
		(8 "In3.Cu" signal "L4VCC")
		(10 "In4.Cu" signal "L5VCC")
		(12 "In5.Cu" signal "L6")
		(14 "In6.Cu" signal "L7GND")
		(2 "B.Cu" signal "BOTTOM")
		(9 "F.Adhes" user "F.Adhesive")
		(11 "B.Adhes" user "B.Adhesive")
		(13 "F.Paste" user "Package Geometry/Pastemask Top")
		(15 "B.Paste" user "Package Geometry/Pastemask Bottom")
		(5 "F.SilkS" user "Ref Des/Silkscreen Top")
		(7 "B.SilkS" user "Ref Des/Silkscreen Bottom")
		(1 "F.Mask" user "Board Geometry/Soldermask Top")
		(3 "B.Mask" user "Board Geometry/Soldermask Bottom")
		(17 "Dwgs.User" user "User.Drawings")
		(19 "Cmts.User" user "User.Comments")
		(21 "Eco1.User" user "User.Eco1")
		(23 "Eco2.User" user "User.Eco2")
		(25 "Edge.Cuts" user "Board Geometry/Outline")
		(27 "Margin" user)
		(31 "F.CrtYd" user "Package Geometry/Place Bound Top")
		(29 "B.CrtYd" user "Package Geometry/Place Bound Bottom")
		(35 "F.Fab" user "Ref Des/Assembly Top")
		(33 "B.Fab" user "Ref Des/Assembly Bottom")
	)
	(footprint ""
		(layer "F.Cu")
		(at 2.500122 -210.00466 -90)
		(property "Reference" "CN6"
			(at 0 0 270)
			(layer "F.SilkS")
			(hide yes)
			(effects
				(font
					(size 1.27 1.27)
				)
			)
		)
		(property "Value" "PCISLT36-27-GP"
			(at 5.281422 -7.491476 270)
			(unlocked yes)
			(layer "F.Fab")
			(hide yes)
			(effects
				(font
					(size 1.016 1.016)
					(thickness 0.1524)
				)
			)
		)
		(property "Device Type" "G630H3612248EU"
			(at 5.281422 -9.015476 270)
			(unlocked yes)
			(layer "F.Fab")
			(hide yes)
			(effects
				(font
					(size 1.016 1.016)
					(thickness 0.1524)
				)
			)
		)
		(duplicate_pad_numbers_are_jumpers no)
		(fp_line
			(start -14.899894 2.499868)
			(end -1.450086 2.499868)
			(stroke
				(width 0.1524)
				(type default)
			)
			(layer "F.SilkS")
		)
		(fp_line
			(start -1.450086 2.499868)
			(end -0.94996 1.999742)
			(stroke
				(width 0.1524)
				(type default)
			)
			(layer "F.SilkS")
		)
		(fp_line
			(start 1.450086 2.499868)
			(end 18.899886 2.499868)
			(stroke
				(width 0.1524)
				(type default)
			)
			(layer "F.SilkS")
		)
		(fp_line
			(start 18.899886 2.499868)
			(end 19.400012 1.999742)
			(stroke
				(width 0.1524)
				(type default)
			)
			(layer "F.SilkS")
		)
		(fp_line
			(start -15.40002 1.999742)
			(end -14.899894 2.499868)
			(stroke
				(width 0.1524)
				(type default)
			)
			(layer "F.SilkS")
		)
		(fp_line
			(start -0.94996 1.999742)
			(end -0.94996 -2.55016)
			(stroke
				(width 0.1524)
				(type default)
			)
			(layer "F.SilkS")
		)
		(fp_line
			(start 0.94996 1.999742)
			(end 1.450086 2.499868)
			(stroke
				(width 0.1524)
				(type default)
			)
			(layer "F.SilkS")
		)
		(fp_line
			(start 19.400012 1.999742)
			(end 19.400012 -4.064)
			(stroke
				(width 0.1524)
				(type default)
			)
			(layer "F.SilkS")
		)
		(fp_line
			(start 0.94996 -2.539746)
			(end 0.94996 1.999742)
			(stroke
				(width 0.1524)
				(type default)
			)
			(layer "F.SilkS")
		)
		(fp_line
			(start 0.94996 -2.55016)
			(end 0.94996 -2.539746)
			(stroke
				(width 0.1524)
				(type default)
			)
			(layer "F.SilkS")
		)
		(fp_line
			(start -15.40002 -4.064)
			(end -15.40002 1.999742)
			(stroke
				(width 0.1524)
				(type default)
			)
			(layer "F.SilkS")
		)
		(fp_line
			(start 19.400012 -4.064)
			(end -15.40002 -4.064)
			(stroke
				(width 0.1524)
				(type default)
			)
			(layer "F.SilkS")
		)
		(fp_line
			(start 11.6713 -4.1529)
			(end 11.2903 -4.1529)
			(stroke
				(width 0.3302)
				(type default)
			)
			(layer "F.SilkS")
		)
		(fp_arc
			(start -0.94996 -2.55016)
			(mid 0 -3.50012)
			(end 0.94996 -2.55016)
			(stroke
				(width 0.1524)
				(type default)
			)
			(layer "F.SilkS")
		)
		(fp_poly
			(pts
				(xy 11.474704 -4.1402) (xy 10.966704 -4.6482) (xy 11.982704 -4.6482)
			)
			(stroke
				(width 0)
				(type default)
			)
			(fill yes)
			(layer "F.SilkS")
		)
		(fp_poly
			(pts
				(xy -10.4902 14.986) (xy -10.4902 4.8006) (xy -15.3924 4.8006) (xy -15.3924 -3.81) (xy 19.4056 -3.81)
				(xy 19.4056 4.8006) (xy 14.5034 4.8006) (xy 14.5034 14.986)
			)
			(stroke
				(width 0)
				(type default)
			)
			(fill no)
			(layer "B.CrtYd")
		)
		(fp_poly
			(pts
				(xy -10.9982 15.494) (xy -10.9982 5.3086) (xy -15.9004 5.3086) (xy -15.9004 -4.318) (xy 19.9136 -4.318)
				(xy 19.9136 5.3086) (xy 15.0114 5.3086) (xy 15.0114 15.494) (xy 0.00254 15.494) (xy 0.00254 14.986)
				(xy 14.5034 14.986) (xy 14.5034 4.8006) (xy 19.4056 4.8006) (xy 19.4056 -3.81) (xy -15.3924 -3.81)
				(xy -15.3924 4.8006) (xy -10.4902 4.8006) (xy -10.4902 14.986) (xy -0.00254 14.986) (xy -0.00254 15.494)
			)
			(stroke
				(width 0)
				(type default)
			)
			(fill no)
			(layer "B.CrtYd")
		)
		(fp_poly
			(pts
				(xy -10.4902 14.986) (xy -10.4902 4.8006) (xy -15.3924 4.8006) (xy -15.3924 -3.81) (xy 19.4056 -3.81)
				(xy 19.4056 4.8006) (xy 14.5034 4.8006) (xy 14.5034 14.986)
			)
			(stroke
				(width 0)
				(type default)
			)
			(fill no)
			(layer "F.CrtYd")
		)
		(fp_poly
			(pts
				(xy -10.9982 15.494) (xy -10.9982 5.3086) (xy -15.9004 5.3086) (xy -15.9004 -4.318) (xy 19.9136 -4.318)
				(xy 19.9136 5.3086) (xy 15.0114 5.3086) (xy 15.0114 15.494) (xy 0.00254 15.494) (xy 0.00254 14.986)
				(xy 14.5034 14.986) (xy 14.5034 4.8006) (xy 19.4056 4.8006) (xy 19.4056 -3.81) (xy -15.3924 -3.81)
				(xy -15.3924 4.8006) (xy -10.4902 4.8006) (xy -10.4902 14.986) (xy -0.00254 14.986) (xy -0.00254 15.494)
			)
			(stroke
				(width 0)
				(type default)
			)
			(fill no)
			(layer "F.CrtYd")
		)
		(fp_poly
			(pts
				(xy -10.9982 15.494) (xy -10.9982 5.3086) (xy -15.9004 5.3086) (xy -15.9004 -4.318) (xy 19.9136 -4.318)
				(xy 19.9136 5.3086) (xy 15.0114 5.3086) (xy 15.0114 15.494)
			)
			(stroke
				(width 0)
				(type default)
			)
			(fill no)
			(layer "B.Fab")
		)
		(fp_poly
			(pts
				(xy -10.9982 15.494) (xy -10.9982 5.3086) (xy -15.9004 5.3086) (xy -15.9004 -4.318) (xy 19.9136 -4.318)
				(xy 19.9136 5.3086) (xy 15.0114 5.3086) (xy 15.0114 15.494)
			)
			(stroke
				(width 0)
				(type default)
			)
			(fill no)
			(layer "F.Fab")
		)
		(fp_text user "Slit"
			(at 1.9304 5.260086 270)
			(unlocked yes)
			(layer "F.SilkS")
			(effects
				(font
					(size 0.635 0.635)
					(thickness 0.1524)
				)
				(justify left)
			)
		)
		(pad "" np_thru_hole circle
			(at -12.300204 0 270)
			(size 0.254 0.254)
			(drill 2.3114)
			(layers "*.Cu" "*.Mask")
			(clearance 1.3843)
			(thermal_gap 1.3843)
		)
		(pad "" np_thru_hole circle
			(at 16.299942 0 270)
			(size 0.254 0.254)
			(drill 2.3114)
			(layers "*.Cu" "*.Mask")
			(clearance 1.3843)
			(thermal_gap 1.3843)
		)
		(pad "A1" smd rect
			(at 11.500104 -0.309118 270)
			(size 0.7112 3.6068)
			(drill
				(offset 0 -0.381)
			)
			(layers "F.Cu" "F.Mask" "F.Paste")
			(net "HDD_PRSNT14")
		)
		(pad "A2" smd rect
			(at 10.500106 -0.309118 270)
			(size 0.7112 3.6068)
			(drill
				(offset 0 -0.381)
			)
			(layers "F.Cu" "F.Mask" "F.Paste")
			(net "HDD_PRSNT4")
		)
		(pad "A3" smd rect
			(at 9.500108 -0.309118 270)
			(size 0.7112 3.6068)
			(drill
				(offset 0 -0.381)
			)
			(layers "F.Cu" "F.Mask" "F.Paste")
			(net "HDD_PRSNT9")
		)
		(pad "A4" smd rect
			(at 8.50011 -0.309118 270)
			(size 0.7112 3.6068)
			(drill
				(offset 0 -0.381)
			)
			(layers "F.Cu" "F.Mask" "F.Paste")
			(net "HDD_PRSNT3")
		)
		(pad "A5" smd rect
			(at 7.500112 -0.309118 270)
			(size 0.7112 3.6068)
			(drill
				(offset 0 -0.381)
			)
			(layers "F.Cu" "F.Mask" "F.Paste")
			(net "HDD_PRSNT2")
		)
		(pad "A6" smd rect
			(at 6.500114 -0.309118 270)
			(size 0.7112 3.6068)
			(drill
				(offset 0 -0.381)
			)
			(layers "F.Cu" "F.Mask" "F.Paste")
			(net "HDD_PRSNT8")
		)
		(pad "A7" smd rect
			(at 5.500116 -0.309118 270)
			(size 0.7112 3.6068)
			(drill
				(offset 0 -0.381)
			)
			(layers "F.Cu" "F.Mask" "F.Paste")
			(net "HDD_PRSNT7")
		)
		(pad "A8" smd rect
			(at 4.500118 -0.309118 270)
			(size 0.7112 3.6068)
			(drill
				(offset 0 -0.381)
			)
			(layers "F.Cu" "F.Mask" "F.Paste")
			(net "HDD_PRSNT1")
		)
		(pad "A9" smd rect
			(at 3.50012 -0.309118 270)
			(size 0.7112 3.6068)
			(drill
				(offset 0 -0.381)
			)
			(layers "F.Cu" "F.Mask" "F.Paste")
			(net "HDD_PRSNT0")
		)
		(pad "A10" smd rect
			(at 2.500122 -0.309118 270)
			(size 0.7112 3.6068)
			(drill
				(offset 0 -0.381)
			)
			(layers "F.Cu" "F.Mask" "F.Paste")
			(net "HDD_PRSNT13")
		)
		(pad "A11" smd rect
			(at 1.500124 -0.309118 270)
			(size 0.7112 3.6068)
			(drill
				(offset 0 -0.381)
			)
			(layers "F.Cu" "F.Mask" "F.Paste")
			(net "HDD_PRSNT6")
		)
		(pad "A12" smd rect
			(at -1.500124 -0.309118 270)
			(size 0.7112 3.6068)
			(drill
				(offset 0 -0.381)
			)
			(layers "F.Cu" "F.Mask" "F.Paste")
			(net "HDD_PRSNT5")
		)
		(pad "A13" smd rect
			(at -2.500122 -0.309118 270)
			(size 0.7112 3.6068)
			(drill
				(offset 0 -0.381)
			)
			(layers "F.Cu" "F.Mask" "F.Paste")
			(net "HDD_PRSNT10")
		)
		(pad "A14" smd rect
			(at -3.50012 -0.309118 270)
			(size 0.7112 3.6068)
			(drill
				(offset 0 -0.381)
			)
			(layers "F.Cu" "F.Mask" "F.Paste")
			(net "HDD_PRSNT11")
		)
		(pad "A15" smd rect
			(at -4.500118 -0.309118 270)
			(size 0.7112 3.6068)
			(drill
				(offset 0 -0.381)
			)
			(layers "F.Cu" "F.Mask" "F.Paste")
			(net "HDD_PRSNT12")
		)
		(pad "A16" smd rect
			(at -5.500116 -0.309118 270)
			(size 0.7112 3.6068)
			(drill
				(offset 0 -0.381)
			)
			(layers "F.Cu" "F.Mask" "F.Paste")
			(net "SELF_TRAY_PRESENT")
		)
		(pad "A17" smd rect
			(at -6.500114 -0.309118 270)
			(size 0.7112 3.6068)
			(drill
				(offset 0 -0.381)
			)
			(layers "F.Cu" "F.Mask" "F.Paste")
			(net "PEER_TRAY_PRESENT")
		)
		(pad "A18" smd rect
			(at -7.500112 -0.309118 270)
			(size 0.7112 3.6068)
			(drill
				(offset 0 -0.381)
			)
			(layers "F.Cu" "F.Mask" "F.Paste")
			(net "EXP_B_PRNST_TX")
		)
		(pad "B1" smd rect
			(at 11.500104 -0.690118 270)
			(size 0.7112 3.6068)
			(layers "F.Cu" "F.Mask" "F.Paste")
			(net "SAS_EXP_B_PWR14")
		)
		(pad "B2" smd rect
			(at 10.500106 -0.690118 270)
			(size 0.7112 3.6068)
			(layers "F.Cu" "F.Mask" "F.Paste")
			(net "SAS_EXP_B_PWR4")
		)
		(pad "B3" smd rect
			(at 9.500108 -0.690118 270)
			(size 0.7112 3.6068)
			(layers "F.Cu" "F.Mask" "F.Paste")
			(net "SAS_EXP_B_PWR9")
		)
		(pad "B4" smd rect
			(at 8.50011 -0.690118 270)
			(size 0.7112 3.6068)
			(layers "F.Cu" "F.Mask" "F.Paste")
			(net "SAS_EXP_B_PWR3")
		)
		(pad "B5" smd rect
			(at 7.500112 -0.690118 270)
			(size 0.7112 3.6068)
			(layers "F.Cu" "F.Mask" "F.Paste")
			(net "SAS_EXP_B_PWR2")
		)
		(pad "B6" smd rect
			(at 6.500114 -0.690118 270)
			(size 0.7112 3.6068)
			(layers "F.Cu" "F.Mask" "F.Paste")
			(net "SAS_EXP_B_PWR8")
		)
		(pad "B7" smd rect
			(at 5.500116 -0.690118 270)
			(size 0.7112 3.6068)
			(layers "F.Cu" "F.Mask" "F.Paste")
			(net "SAS_EXP_B_PWR7")
		)
		(pad "B8" smd rect
			(at 4.500118 -0.690118 270)
			(size 0.7112 3.6068)
			(layers "F.Cu" "F.Mask" "F.Paste")
			(net "SAS_EXP_B_PWR1")
		)
		(pad "B9" smd rect
			(at 3.50012 -0.690118 270)
			(size 0.7112 3.6068)
			(layers "F.Cu" "F.Mask" "F.Paste")
			(net "SAS_EXP_B_PWR0")
		)
		(pad "B10" smd rect
			(at 2.500122 -0.690118 270)
			(size 0.7112 3.6068)
			(layers "F.Cu" "F.Mask" "F.Paste")
			(net "SAS_EXP_B_PWR13")
		)
		(pad "B11" smd rect
			(at 1.500124 -0.690118 270)
			(size 0.7112 3.6068)
			(layers "F.Cu" "F.Mask" "F.Paste")
			(net "SAS_EXP_B_PWR6")
		)
		(pad "B12" smd rect
			(at -1.500124 -0.690118 270)
			(size 0.7112 3.6068)
			(layers "F.Cu" "F.Mask" "F.Paste")
			(net "SAS_EXP_B_PWR5")
		)
		(pad "B13" smd rect
			(at -2.500122 -0.690118 270)
			(size 0.7112 3.6068)
			(layers "F.Cu" "F.Mask" "F.Paste")
			(net "SAS_EXP_B_PWR10")
		)
		(pad "B14" smd rect
			(at -3.50012 -0.690118 270)
			(size 0.7112 3.6068)
			(layers "F.Cu" "F.Mask" "F.Paste")
			(net "SAS_EXP_B_PWR11")
		)
		(pad "B15" smd rect
			(at -4.500118 -0.690118 270)
			(size 0.7112 3.6068)
			(layers "F.Cu" "F.Mask" "F.Paste")
			(net "SAS_EXP_B_PWR12")
		)
		(pad "B16" smd rect
			(at -5.500116 -0.690118 270)
			(size 0.7112 3.6068)
			(layers "F.Cu" "F.Mask" "F.Paste")
			(net "SAS_EXP_B_PWR15")
		)
		(pad "B17" smd rect
			(at -6.500114 -0.690118 270)
			(size 0.7112 3.6068)
			(layers "F.Cu" "F.Mask" "F.Paste")
			(net "PCIE_MATED#_B")
		)
		(pad "B18" smd rect
			(at -7.500112 -0.690118 270)
			(size 0.7112 3.6068)
			(layers "F.Cu" "F.Mask" "F.Paste")
			(net "EXP_A_PRNST_RX")
		)
		(zone
			(layers "F.Cu" "B.Cu" "In1.Cu" "In2.Cu" "In3.Cu" "In4.Cu" "In5.Cu" "In6.Cu")
			(hatch none 0.5)
			(connect_pads
				(clearance 0)
			)
			(min_thickness 0.25)
			(keepout
				(tracks not_allowed)
				(vias allowed)
				(pads allowed)
				(copperpour not_allowed)
				(footprints allowed)
			)
			(placement
				(enabled no)
				(sheetname "")
			)
			(fill
				(thermal_gap 0.5)
				(thermal_bridge_width 0.5)
				(island_removal_mode 0)
			)
			(polygon
				(pts
					(arc
						(start 3.960622 -222.304864)
						(mid 1.039622 -222.304864)
						(end 3.960622 -222.304864)
					)
				)
			)
		)
		(zone
			(layers "F.Cu" "B.Cu" "In1.Cu" "In2.Cu" "In3.Cu" "In4.Cu" "In5.Cu" "In6.Cu")
			(hatch none 0.5)
			(connect_pads
				(clearance 0)
			)
			(min_thickness 0.25)
			(keepout
				(tracks not_allowed)
				(vias allowed)
				(pads allowed)
				(copperpour not_allowed)
				(footprints allowed)
			)
			(placement
				(enabled no)
				(sheetname "")
			)
			(fill
				(thermal_gap 0.5)
				(thermal_bridge_width 0.5)
				(island_removal_mode 0)
			)
			(polygon
				(pts
					(arc
						(start 3.960622 -193.704718)
						(mid 1.039622 -193.704718)
						(end 3.960622 -193.704718)
					)
				)
			)
		)
	)
	(footprint ""
		(layer "F.Cu")
		(at 8.5852 -150.6982 90)
		(property "Reference" "R546"
			(at 0 0 90)
			(layer "F.SilkS")
			(hide yes)
			(effects
				(font
					(size 1.27 1.27)
				)
			)
		)
		(property "Value" "0R2J-2-GP"
			(at 0.064008 -3.993896 90)
			(unlocked yes)
			(layer "F.Fab")
			(hide yes)
			(effects
				(font
					(size 1.016 1.016)
					(thickness 0.1524)
				)
			)
		)
		(property "Device Type" "R402H16"
			(at 0.064008 -5.517896 90)
			(unlocked yes)
			(layer "F.Fab")
			(hide yes)
			(effects
				(font
					(size 1.016 1.016)
					(thickness 0.1524)
				)
			)
		)
		(duplicate_pad_numbers_are_jumpers no)
		(fp_line
			(start 0.508 -0.9398)
			(end -0.508 -0.9398)
			(stroke
				(width 0.1524)
				(type default)
			)
			(layer "F.SilkS")
		)
		(fp_line
			(start -0.508 -0.9398)
			(end -0.508 0.9398)
			(stroke
				(width 0.1524)
				(type default)
			)
			(layer "F.SilkS")
		)
		(fp_rect
			(start -0.508 0.9398)
			(end 0.508 -0.9398)
			(stroke
				(width 0)
				(type default)
			)
			(fill no)
			(layer "F.CrtYd")
		)
		(fp_rect
			(start -0.508 0.9398)
			(end 0.508 -0.9398)
			(stroke
				(width 0)
				(type default)
			)
			(fill no)
			(layer "F.Fab")
		)
		(pad "1" smd custom
			(at 0 -0.4445 90)
			(size 0.1397 0.1397)
			(layers "F.Cu" "F.Mask" "F.Paste")
			(net "I2C_C_SCL_DAMP_B")
			(options
				(clearance outline)
				(anchor circle)
			)
			(primitives
				(gr_poly
					(pts
						(arc
							(start -0.1778 -0.2794)
							(mid -0.249642 -0.249642)
							(end -0.2794 -0.1778)
						)
						(arc
							(start -0.2794 0.1778)
							(mid -0.249642 0.249642)
							(end -0.1778 0.2794)
						)
						(arc
							(start 0.1778 0.2794)
							(mid 0.249642 0.249642)
							(end 0.2794 0.1778)
						)
						(arc
							(start 0.2794 -0.1778)
							(mid 0.249642 -0.249642)
							(end 0.1778 -0.2794)
						)
					)
					(width 0)
					(fill yes)
				)
			)
		)
		(pad "2" smd custom
			(at 0 0.4445 90)
			(size 0.1397 0.1397)
			(layers "F.Cu" "F.Mask" "F.Paste")
			(net "I2C_C_SCL")
			(options
				(clearance outline)
				(anchor circle)
			)
			(primitives
				(gr_poly
					(pts
						(arc
							(start -0.1778 -0.2794)
							(mid -0.249642 -0.249642)
							(end -0.2794 -0.1778)
						)
						(arc
							(start -0.2794 0.1778)
							(mid -0.249642 0.249642)
							(end -0.1778 0.2794)
						)
						(arc
							(start 0.1778 0.2794)
							(mid 0.249642 0.249642)
							(end 0.2794 0.1778)
						)
						(arc
							(start 0.2794 -0.1778)
							(mid 0.249642 -0.249642)
							(end 0.1778 -0.2794)
						)
					)
					(width 0)
					(fill yes)
				)
			)
		)
	)
	(footprint ""
		(layer "F.Cu")
		(at 58.927746 -26.6827 -90)
		(property "Reference" "PR22"
			(at 0 0 270)
			(layer "F.SilkS")
			(hide yes)
			(effects
				(font
					(size 1.27 1.27)
				)
			)
		)
		(property "Value" "866KR2F-GP"
			(at 0.064008 -3.993896 270)
			(unlocked yes)
			(layer "F.Fab")
			(hide yes)
			(effects
				(font
					(size 1.016 1.016)
					(thickness 0.1524)
				)
			)
		)
		(property "Device Type" "R402H16"
			(at 0.064008 -5.517896 270)
			(unlocked yes)
			(layer "F.Fab")
			(hide yes)
			(effects
				(font
					(size 1.016 1.016)
					(thickness 0.1524)
				)
			)
		)
		(duplicate_pad_numbers_are_jumpers no)
		(fp_line
			(start -0.508 -0.9398)
			(end -0.508 0.9398)
			(stroke
				(width 0.1524)
				(type default)
			)
			(layer "F.SilkS")
		)
		(fp_line
			(start 0.508 -0.9398)
			(end -0.508 -0.9398)
			(stroke
				(width 0.1524)
				(type default)
			)
			(layer "F.SilkS")
		)
		(fp_rect
			(start -0.508 0.9398)
			(end 0.508 -0.9398)
			(stroke
				(width 0)
				(type default)
			)
			(fill no)
			(layer "F.CrtYd")
		)
		(fp_rect
			(start -0.508 0.9398)
			(end 0.508 -0.9398)
			(stroke
				(width 0)
				(type default)
			)
			(fill no)
			(layer "F.Fab")
		)
		(pad "1" smd custom
			(at 0 -0.4445 270)
			(size 0.1397 0.1397)
			(layers "F.Cu" "F.Mask" "F.Paste")
			(net "P5VB_VREG")
			(options
				(clearance outline)
				(anchor circle)
			)
			(primitives
				(gr_poly
					(pts
						(arc
							(start -0.1778 -0.2794)
							(mid -0.249642 -0.249642)
							(end -0.2794 -0.1778)
						)
						(arc
							(start -0.2794 0.1778)
							(mid -0.249642 0.249642)
							(end -0.1778 0.2794)
						)
						(arc
							(start 0.1778 0.2794)
							(mid 0.249642 0.249642)
							(end 0.2794 0.1778)
						)
						(arc
							(start 0.2794 -0.1778)
							(mid 0.249642 -0.249642)
							(end 0.1778 -0.2794)
						)
					)
					(width 0)
					(fill yes)
				)
			)
		)
		(pad "2" smd custom
			(at 0 0.4445 270)
			(size 0.1397 0.1397)
			(layers "F.Cu" "F.Mask" "F.Paste")
			(net "P5VB_RF")
			(options
				(clearance outline)
				(anchor circle)
			)
			(primitives
				(gr_poly
					(pts
						(arc
							(start -0.1778 -0.2794)
							(mid -0.249642 -0.249642)
							(end -0.2794 -0.1778)
						)
						(arc
							(start -0.2794 0.1778)
							(mid -0.249642 0.249642)
							(end -0.1778 0.2794)
						)
						(arc
							(start 0.1778 0.2794)
							(mid 0.249642 0.249642)
							(end 0.2794 0.1778)
						)
						(arc
							(start 0.2794 -0.1778)
							(mid 0.249642 -0.249642)
							(end 0.1778 -0.2794)
						)
					)
					(width 0)
					(fill yes)
				)
			)
		)
	)
)
